# S9S_MB_2U (Grand Teton) — schematic netlist excerpt (pin names and nets, part order shuffled) for the footprints in the layout excerpt that follows; sources: Cadence DE-HDL packaged netlist, KiCad conversion of 03242023_DA0F0TMBIJ0_F0T_Motherboard_J_brd_V01_OCP.brd

R1319  Q_RES  2K 1% EMPTY  pkg 0402LF  page 241 : A = SMB_HOST_3V3AUX_SCL ; B = P3V3_AUX
R1239  Q_RES  240 1% EMPTY  pkg 0402LF  page 119 : A = GND ; B = PUD_XTAL_CPU0_MODE1

(kicad_pcb
	(version 20260206)
	(generator "pcbnew")
	(generator_version "10.0")
	(general
		(thickness 1.6)
		(legacy_teardrops no)
	)
	(paper "A4")
	(title_block
		(title "03242023_DA0F0TMBIJ0_F0T_Motherboard_J_brd_V01_OCP.brd")
		(comment 1 "Grand Teton / footprints 4560-4561 of 6105")
	)
	(layers
		(0 "F.Cu" signal "TOP")
		(4 "In1.Cu" signal "GND")
		(6 "In2.Cu" signal "IN1")
		(8 "In3.Cu" signal "GND1")
		(10 "In4.Cu" signal "IN2")
		(12 "In5.Cu" signal "GND2")
		(14 "In6.Cu" signal "IN3")
		(16 "In7.Cu" signal "GND3")
		(18 "In8.Cu" signal "VCC")
		(20 "In9.Cu" signal "VCC1")
		(22 "In10.Cu" signal "GND4")
		(24 "In11.Cu" signal "IN4")
		(26 "In12.Cu" signal "GND5")
		(28 "In13.Cu" signal "IN5")
		(30 "In14.Cu" signal "GND6")
		(32 "In15.Cu" signal "IN6")
		(34 "In16.Cu" signal "GND7")
		(2 "B.Cu" signal "BOTTOM")
		(9 "F.Adhes" user "F.Adhesive")
		(11 "B.Adhes" user "B.Adhesive")
		(13 "F.Paste" user "Package Geometry/Pastemask Top")
		(15 "B.Paste" user "Package Geometry/Pastemask Bottom")
		(5 "F.SilkS" user "Ref Des/Silkscreen Top")
		(7 "B.SilkS" user "Ref Des/Silkscreen Bottom")
		(1 "F.Mask" user "Board Geometry/Soldermask Top")
		(3 "B.Mask" user "Board Geometry/Soldermask Bottom")
		(17 "Dwgs.User" user "User.Drawings")
		(19 "Cmts.User" user "User.Comments")
		(21 "Eco1.User" user "User.Eco1")
		(23 "Eco2.User" user "User.Eco2")
		(25 "Edge.Cuts" user "Board Geometry/Outline")
		(27 "Margin" user)
		(31 "F.CrtYd" user "Package Geometry/Place Bound Top")
		(29 "B.CrtYd" user "Package Geometry/Place Bound Bottom")
		(35 "F.Fab" user "Ref Des/Assembly Top")
		(33 "B.Fab" user "Ref Des/Assembly Bottom")
	)
	(footprint ""
		(layer "B.Cu")
		(at 404.09241 -194.87007 90)
		(property "Reference" "R1239"
			(at 0 0 90)
			(layer "B.SilkS")
			(hide yes)
			(effects
				(font
					(size 1.27 1.27)
				)
				(justify mirror)
			)
		)
		(property "Value" ""
			(at 0 0 90)
			(layer "B.Fab")
			(effects
				(font
					(size 1.27 1.27)
				)
				(justify mirror)
			)
		)
		(duplicate_pad_numbers_are_jumpers no)
		(fp_line
			(start 0.7874 -0.4064)
			(end -0.7874 -0.4064)
			(stroke
				(width 0.1524)
				(type default)
			)
			(layer "B.SilkS")
		)
		(fp_line
			(start -0.7874 -0.4064)
			(end -0.7874 0.4064)
			(stroke
				(width 0.1524)
				(type default)
			)
			(layer "B.SilkS")
		)
		(fp_line
			(start 0.7874 0.4064)
			(end 0.7874 -0.4064)
			(stroke
				(width 0.1524)
				(type default)
			)
			(layer "B.SilkS")
		)
		(fp_line
			(start -0.7874 0.4064)
			(end 0.7874 0.4064)
			(stroke
				(width 0.1524)
				(type default)
			)
			(layer "B.SilkS")
		)
		(fp_line
			(start 0.67945 -0.305054)
			(end 0.12065 -0.305054)
			(stroke
				(width 0.1)
				(type default)
			)
			(layer "B.Fab")
		)
		(fp_line
			(start 0.12065 -0.305054)
			(end 0.12065 -0.2794)
			(stroke
				(width 0.1)
				(type default)
			)
			(layer "B.Fab")
		)
		(fp_line
			(start -0.12065 -0.3048)
			(end -0.67945 -0.3048)
			(stroke
				(width 0.1)
				(type default)
			)
			(layer "B.Fab")
		)
		(fp_line
			(start -0.67945 -0.3048)
			(end -0.67945 0.3048)
			(stroke
				(width 0.1)
				(type default)
			)
			(layer "B.Fab")
		)
		(fp_line
			(start 0.12065 -0.2794)
			(end -0.12065 -0.2794)
			(stroke
				(width 0.1)
				(type default)
			)
			(layer "B.Fab")
		)
		(fp_line
			(start -0.12065 -0.2794)
			(end -0.12065 -0.3048)
			(stroke
				(width 0.1)
				(type default)
			)
			(layer "B.Fab")
		)
		(fp_line
			(start 0.12065 0.2794)
			(end 0.12065 0.3048)
			(stroke
				(width 0.1)
				(type default)
			)
			(layer "B.Fab")
		)
		(fp_line
			(start -0.120396 0.2794)
			(end 0.12065 0.2794)
			(stroke
				(width 0.1)
				(type default)
			)
			(layer "B.Fab")
		)
		(fp_line
			(start 0.67945 0.3048)
			(end 0.67945 -0.305054)
			(stroke
				(width 0.1)
				(type default)
			)
			(layer "B.Fab")
		)
		(fp_line
			(start 0.12065 0.3048)
			(end 0.67945 0.3048)
			(stroke
				(width 0.1)
				(type default)
			)
			(layer "B.Fab")
		)
		(fp_line
			(start -0.120396 0.3048)
			(end -0.120396 0.2794)
			(stroke
				(width 0.1)
				(type default)
			)
			(layer "B.Fab")
		)
		(fp_line
			(start -0.67945 0.3048)
			(end -0.120396 0.3048)
			(stroke
				(width 0.1)
				(type default)
			)
			(layer "B.Fab")
		)
		(pad "1" smd circle
			(at 0.40005 0 270)
			(size 0 0)
			(layers "B.Cu" "B.Mask" "B.Paste")
			(net "GND")
		)
		(pad "2" smd circle
			(at -0.40005 0 270)
			(size 0 0)
			(layers "B.Cu" "B.Mask" "B.Paste")
			(net "PUD_XTAL_CPU0_MODE1")
		)
	)
	(footprint ""
		(layer "B.Cu")
		(at 183.7436 -21.351748 -90)
		(property "Reference" "R1319"
			(at 0 0 90)
			(layer "B.SilkS")
			(hide yes)
			(effects
				(font
					(size 1.27 1.27)
				)
				(justify mirror)
			)
		)
		(property "Value" ""
			(at 0 0 90)
			(layer "B.Fab")
			(effects
				(font
					(size 1.27 1.27)
				)
				(justify mirror)
			)
		)
		(duplicate_pad_numbers_are_jumpers no)
		(fp_line
			(start -0.7874 0.4064)
			(end 0.7874 0.4064)
			(stroke
				(width 0.1524)
				(type default)
			)
			(layer "B.SilkS")
		)
		(fp_line
			(start 0.7874 0.4064)
			(end 0.7874 -0.4064)
			(stroke
				(width 0.1524)
				(type default)
			)
			(layer "B.SilkS")
		)
		(fp_line
			(start -0.7874 -0.4064)
			(end -0.7874 0.4064)
			(stroke
				(width 0.1524)
				(type default)
			)
			(layer "B.SilkS")
		)
		(fp_line
			(start 0.7874 -0.4064)
			(end -0.7874 -0.4064)
			(stroke
				(width 0.1524)
				(type default)
			)
			(layer "B.SilkS")
		)
		(fp_line
			(start -0.67945 0.3048)
			(end -0.120396 0.3048)
			(stroke
				(width 0.1)
				(type default)
			)
			(layer "B.Fab")
		)
		(fp_line
			(start -0.120396 0.3048)
			(end -0.120396 0.2794)
			(stroke
				(width 0.1)
				(type default)
			)
			(layer "B.Fab")
		)
		(fp_line
			(start 0.12065 0.3048)
			(end 0.67945 0.3048)
			(stroke
				(width 0.1)
				(type default)
			)
			(layer "B.Fab")
		)
		(fp_line
			(start 0.67945 0.3048)
			(end 0.67945 -0.305054)
			(stroke
				(width 0.1)
				(type default)
			)
			(layer "B.Fab")
		)
		(fp_line
			(start -0.120396 0.2794)
			(end 0.12065 0.2794)
			(stroke
				(width 0.1)
				(type default)
			)
			(layer "B.Fab")
		)
		(fp_line
			(start 0.12065 0.2794)
			(end 0.12065 0.3048)
			(stroke
				(width 0.1)
				(type default)
			)
			(layer "B.Fab")
		)
		(fp_line
			(start -0.12065 -0.2794)
			(end -0.12065 -0.3048)
			(stroke
				(width 0.1)
				(type default)
			)
			(layer "B.Fab")
		)
		(fp_line
			(start 0.12065 -0.2794)
			(end -0.12065 -0.2794)
			(stroke
				(width 0.1)
				(type default)
			)
			(layer "B.Fab")
		)
		(fp_line
			(start -0.67945 -0.3048)
			(end -0.67945 0.3048)
			(stroke
				(width 0.1)
				(type default)
			)
			(layer "B.Fab")
		)
		(fp_line
			(start -0.12065 -0.3048)
			(end -0.67945 -0.3048)
			(stroke
				(width 0.1)
				(type default)
			)
			(layer "B.Fab")
		)
		(fp_line
			(start 0.12065 -0.305054)
			(end 0.12065 -0.2794)
			(stroke
				(width 0.1)
				(type default)
			)
			(layer "B.Fab")
		)
		(fp_line
			(start 0.67945 -0.305054)
			(end 0.12065 -0.305054)
			(stroke
				(width 0.1)
				(type default)
			)
			(layer "B.Fab")
		)
		(pad "1" smd circle
			(at 0.40005 0 90)
			(size 0 0)
			(layers "B.Cu" "B.Mask" "B.Paste")
			(net "SMB_HOST_3V3AUX_SCL")
		)
		(pad "2" smd circle
			(at -0.40005 0 90)
			(size 0 0)
			(layers "B.Cu" "B.Mask" "B.Paste")
			(net "P3V3_AUX")
		)
	)
)
